#ISCELL
  mstr_misc dns *
  *
#ISCELL
  mstr_symbols intel_corp_bpage *
  *
#ISCELL
  mstr_symbols pvddq_klm *
  page227_i1
#CELL
  mstr_discrete ir354xx *
  page227_i101
#CELL
  mstr_discrete ir354xx *
  page227_i102
#CELL
  mstr_discrete res *
  page227_i103
#ISCELL
  mstr_symbols gnd *
  page227_i104
#CELL
  mstr_discrete res *
  page227_i105
#ISCELL
  mstr_symbols gnd *
  page227_i106
#ISCELL
  mstr_symbols p5v_stby *
  page227_i107
#CELL
  dev_discrete cap_a *
  page227_i109
#ISCELL
  mstr_symbols gnd *
  page227_i110
#ISCELL
  mstr_symbols gnd *
  page227_i113
#CELL
  mstr_discrete cap *
  page227_i114
#ISCELL
  mstr_symbols gnd *
  page227_i115
#ISCELL
  mstr_symbols gnd *
  page227_i117
#CELL
  mstr_discrete cap *
  page227_i119
#ISCELL
  mstr_symbols gnd *
  page227_i120
#CELL
  dev_discrete cap_a *
  page227_i122
#ISCELL
  mstr_symbols gnd *
  page227_i123
#CELL
  mstr_discrete cap *
  page227_i134
#CELL
  mstr_discrete cap *
  page227_i135
#CELL
  mstr_discrete res *
  page227_i138
#CELL
  mstr_discrete res *
  page227_i139
#CELL
  w_hdl sc1u10v2kx-4-gp *
  page227_i147
#CELL
  w_hdl sc1u10v2kx-4-gp *
  page227_i148
#CELL
  w_hdl 1r3f-gp *
  page227_i149
#CELL
  w_hdl 1r3f-gp *
  page227_i150
#CELL
  w_hdl ind-120nh-30-gp *
  page227_i152
#CELL
  w_hdl ind-120nh-30-gp *
  page227_i153
#CELL
  mstr_discrete res *
  page227_i154
#CELL
  mstr_discrete res *
  page227_i155
#ISCELL
  mstr_symbols gnd *
  page227_i19
#ISCELL
  mstr_standard offpage *
  page227_i3
#ISCELL
  mstr_standard offpage *
  page227_i33
#ISCELL
  mstr_symbols gnd *
  page227_i35
#ISCELL
  mstr_standard offpage *
  page227_i4
#CELL
  mstr_discrete cap *
  page227_i44
#CELL
  mstr_discrete cap *
  page227_i45
#CELL
  mstr_discrete cap *
  page227_i46
#CELL
  mstr_discrete cap *
  page227_i47
#CELL
  mstr_discrete cap *
  page227_i48
#CELL
  mstr_discrete cap *
  page227_i50
#CELL
  dev_discrete cap_a *
  page227_i51
#CELL
  mstr_discrete cap *
  page227_i54
#ISCELL
  mstr_standard offpage *
  page227_i58
#CELL
  mstr_discrete cap *
  page227_i6
#ISCELL
  mstr_standard offpage *
  page227_i61
#ISCELL
  mstr_standard offpage *
  page227_i62
#ISCELL
  mstr_standard offpage *
  page227_i63
#ISCELL
  mstr_symbols pvddq_klm *
  page227_i64
#CELL
  mstr_discrete cap *
  page227_i68
#ISCELL
  mstr_symbols gnd *
  page227_i69
#ISCELL
  mstr_symbols gnd *
  page227_i7
#ISCELL
  mstr_symbols gnd *
  page227_i70
#CELL
  mstr_discrete cap *
  page227_i72
#CELL
  mstr_discrete cap *
  page227_i75
#CELL
  mstr_discrete cap *
  page227_i77
#CELL
  dev_discrete cap_a *
  page227_i78
#CELL
  mstr_discrete cap *
  page227_i79
#CELL
  mstr_discrete cap *
  page227_i80
#CELL
  mstr_discrete cap *
  page227_i81
#ISCELL
  mstr_standard offpage *
  page227_i82
#ISCELL
  mstr_symbols vcc_core *
  page227_i83
#CELL
  mstr_discrete cap *
  page227_i84
#ISCELL
  mstr_symbols gnd *
  page227_i85
#ISCELL
  mstr_symbols vcc_core *
  page227_i86
#ISCELL
  mstr_symbols p5v_stby *
  page227_i88
